(kicad_pcb
	(version 20260206)
	(generator "pcbnew")
	(generator_version "10.0")
	(general
		(thickness 1.6)
		(legacy_teardrops no)
	)
	(paper "A4")
	(title_block
		(title "04192023_DAF0TMB3IC0_F0TG_MB_C_brd_V02_OCP.brd")
		(comment 1 "Grand Teton / footprints 6049-6055 of 8354")
	)
	(layers
		(0 "F.Cu" signal "TOP")
		(4 "In1.Cu" signal "GND")
		(6 "In2.Cu" signal "IN1")
		(8 "In3.Cu" signal "GND1")
		(10 "In4.Cu" signal "IN2")
		(12 "In5.Cu" signal "GND2")
		(14 "In6.Cu" signal "IN3")
		(16 "In7.Cu" signal "GND3")
		(18 "In8.Cu" signal "VCC")
		(20 "In9.Cu" signal "VCC1")
		(22 "In10.Cu" signal "GND4")
		(24 "In11.Cu" signal "IN4")
		(26 "In12.Cu" signal "GND5")
		(28 "In13.Cu" signal "IN5")
		(30 "In14.Cu" signal "GND6")
		(32 "In15.Cu" signal "IN6")
		(34 "In16.Cu" signal "GND7")
		(2 "B.Cu" signal "BOTTOM")
		(9 "F.Adhes" user "F.Adhesive")
		(11 "B.Adhes" user "B.Adhesive")
		(13 "F.Paste" user "Package Geometry/Pastemask Top")
		(15 "B.Paste" user "Package Geometry/Pastemask Bottom")
		(5 "F.SilkS" user "Ref Des/Silkscreen Top")
		(7 "B.SilkS" user "Ref Des/Silkscreen Bottom")
		(1 "F.Mask" user "Board Geometry/Soldermask Top")
		(3 "B.Mask" user "Board Geometry/Soldermask Bottom")
		(17 "Dwgs.User" user "User.Drawings")
		(19 "Cmts.User" user "User.Comments")
		(21 "Eco1.User" user "User.Eco1")
		(23 "Eco2.User" user "User.Eco2")
		(25 "Edge.Cuts" user "Board Geometry/Outline")
		(27 "Margin" user)
		(31 "F.CrtYd" user "Package Geometry/Place Bound Top")
		(29 "B.CrtYd" user "Package Geometry/Place Bound Bottom")
		(35 "F.Fab" user "Ref Des/Assembly Top")
		(33 "B.Fab" user "Ref Des/Assembly Bottom")
	)
	(footprint ""
		(layer "B.Cu")
		(at 353.900232 -261.255002 180)
		(property "Reference" "C2145"
			(at 0 0 0)
			(layer "B.SilkS")
			(hide yes)
			(effects
				(font
					(size 1.27 1.27)
				)
				(justify mirror)
			)
		)
		(property "Value" ""
			(at 0 0 0)
			(layer "B.Fab")
			(effects
				(font
					(size 1.27 1.27)
				)
				(justify mirror)
			)
		)
		(duplicate_pad_numbers_are_jumpers no)
		(fp_line
			(start 0.7874 0.4064)
			(end 0.7874 -0.4064)
			(stroke
				(width 0.1524)
				(type default)
			)
			(layer "B.SilkS")
		)
		(fp_line
			(start 0.7874 -0.4064)
			(end -0.7874 -0.4064)
			(stroke
				(width 0.1524)
				(type default)
			)
			(layer "B.SilkS")
		)
		(fp_line
			(start -0.7874 0.4064)
			(end 0.7874 0.4064)
			(stroke
				(width 0.1524)
				(type default)
			)
			(layer "B.SilkS")
		)
		(fp_line
			(start -0.7874 -0.4064)
			(end -0.7874 0.4064)
			(stroke
				(width 0.1524)
				(type default)
			)
			(layer "B.SilkS")
		)
		(fp_line
			(start 0.67945 0.3048)
			(end 0.67945 -0.305054)
			(stroke
				(width 0.1)
				(type default)
			)
			(layer "B.Fab")
		)
		(fp_line
			(start 0.67945 -0.305054)
			(end 0.12065 -0.305054)
			(stroke
				(width 0.1)
				(type default)
			)
			(layer "B.Fab")
		)
		(fp_line
			(start 0.12065 0.3048)
			(end 0.67945 0.3048)
			(stroke
				(width 0.1)
				(type default)
			)
			(layer "B.Fab")
		)
		(fp_line
			(start 0.12065 0.2794)
			(end 0.12065 0.3048)
			(stroke
				(width 0.1)
				(type default)
			)
			(layer "B.Fab")
		)
		(fp_line
			(start 0.12065 -0.2794)
			(end -0.12065 -0.2794)
			(stroke
				(width 0.1)
				(type default)
			)
			(layer "B.Fab")
		)
		(fp_line
			(start 0.12065 -0.305054)
			(end 0.12065 -0.2794)
			(stroke
				(width 0.1)
				(type default)
			)
			(layer "B.Fab")
		)
		(fp_line
			(start -0.120396 0.3048)
			(end -0.120396 0.2794)
			(stroke
				(width 0.1)
				(type default)
			)
			(layer "B.Fab")
		)
		(fp_line
			(start -0.120396 0.2794)
			(end 0.12065 0.2794)
			(stroke
				(width 0.1)
				(type default)
			)
			(layer "B.Fab")
		)
		(fp_line
			(start -0.12065 -0.2794)
			(end -0.12065 -0.3048)
			(stroke
				(width 0.1)
				(type default)
			)
			(layer "B.Fab")
		)
		(fp_line
			(start -0.12065 -0.3048)
			(end -0.67945 -0.3048)
			(stroke
				(width 0.1)
				(type default)
			)
			(layer "B.Fab")
		)
		(fp_line
			(start -0.67945 0.3048)
			(end -0.120396 0.3048)
			(stroke
				(width 0.1)
				(type default)
			)
			(layer "B.Fab")
		)
		(fp_line
			(start -0.67945 -0.3048)
			(end -0.67945 0.3048)
			(stroke
				(width 0.1)
				(type default)
			)
			(layer "B.Fab")
		)
		(pad "1" smd circle
			(at 0.40005 0)
			(size 0 0)
			(layers "B.Cu" "B.Mask" "B.Paste")
			(net "PVDDIO_P0")
		)
		(pad "2" smd circle
			(at -0.40005 0)
			(size 0 0)
			(layers "B.Cu" "B.Mask" "B.Paste")
			(net "GND")
		)
	)
	(footprint ""
		(layer "B.Cu")
		(at 396.142972 -200.754996 90)
		(property "Reference" "R6134"
			(at 0 0 90)
			(layer "B.SilkS")
			(hide yes)
			(effects
				(font
					(size 1.27 1.27)
				)
				(justify mirror)
			)
		)
		(property "Value" ""
			(at 0 0 90)
			(layer "B.Fab")
			(effects
				(font
					(size 1.27 1.27)
				)
				(justify mirror)
			)
		)
		(duplicate_pad_numbers_are_jumpers no)
		(fp_line
			(start 0.7874 -0.4064)
			(end -0.7874 -0.4064)
			(stroke
				(width 0.1524)
				(type default)
			)
			(layer "B.SilkS")
		)
		(fp_line
			(start -0.7874 -0.4064)
			(end -0.7874 0.4064)
			(stroke
				(width 0.1524)
				(type default)
			)
			(layer "B.SilkS")
		)
		(fp_line
			(start 0.7874 0.4064)
			(end 0.7874 -0.4064)
			(stroke
				(width 0.1524)
				(type default)
			)
			(layer "B.SilkS")
		)
		(fp_line
			(start -0.7874 0.4064)
			(end 0.7874 0.4064)
			(stroke
				(width 0.1524)
				(type default)
			)
			(layer "B.SilkS")
		)
		(fp_line
			(start 0.67945 -0.305054)
			(end 0.12065 -0.305054)
			(stroke
				(width 0.1)
				(type default)
			)
			(layer "B.Fab")
		)
		(fp_line
			(start 0.12065 -0.305054)
			(end 0.12065 -0.2794)
			(stroke
				(width 0.1)
				(type default)
			)
			(layer "B.Fab")
		)
		(fp_line
			(start -0.12065 -0.3048)
			(end -0.67945 -0.3048)
			(stroke
				(width 0.1)
				(type default)
			)
			(layer "B.Fab")
		)
		(fp_line
			(start -0.67945 -0.3048)
			(end -0.67945 0.3048)
			(stroke
				(width 0.1)
				(type default)
			)
			(layer "B.Fab")
		)
		(fp_line
			(start 0.12065 -0.2794)
			(end -0.12065 -0.2794)
			(stroke
				(width 0.1)
				(type default)
			)
			(layer "B.Fab")
		)
		(fp_line
			(start -0.12065 -0.2794)
			(end -0.12065 -0.3048)
			(stroke
				(width 0.1)
				(type default)
			)
			(layer "B.Fab")
		)
		(fp_line
			(start 0.12065 0.2794)
			(end 0.12065 0.3048)
			(stroke
				(width 0.1)
				(type default)
			)
			(layer "B.Fab")
		)
		(fp_line
			(start -0.120396 0.2794)
			(end 0.12065 0.2794)
			(stroke
				(width 0.1)
				(type default)
			)
			(layer "B.Fab")
		)
		(fp_line
			(start 0.67945 0.3048)
			(end 0.67945 -0.305054)
			(stroke
				(width 0.1)
				(type default)
			)
			(layer "B.Fab")
		)
		(fp_line
			(start 0.12065 0.3048)
			(end 0.67945 0.3048)
			(stroke
				(width 0.1)
				(type default)
			)
			(layer "B.Fab")
		)
		(fp_line
			(start -0.120396 0.3048)
			(end -0.120396 0.2794)
			(stroke
				(width 0.1)
				(type default)
			)
			(layer "B.Fab")
		)
		(fp_line
			(start -0.67945 0.3048)
			(end -0.120396 0.3048)
			(stroke
				(width 0.1)
				(type default)
			)
			(layer "B.Fab")
		)
		(pad "1" smd circle
			(at 0.40005 0 270)
			(size 0 0)
			(layers "B.Cu" "B.Mask" "B.Paste")
			(net "FAB_REV_ID1")
		)
		(pad "2" smd circle
			(at -0.40005 0 270)
			(size 0 0)
			(layers "B.Cu" "B.Mask" "B.Paste")
			(net "GND")
		)
	)
	(footprint ""
		(layer "B.Cu")
		(at 108.526834 -249.368564 180)
		(property "Reference" "C2298"
			(at 0 0 0)
			(layer "B.SilkS")
			(hide yes)
			(effects
				(font
					(size 1.27 1.27)
				)
				(justify mirror)
			)
		)
		(property "Value" ""
			(at 0 0 0)
			(layer "B.Fab")
			(effects
				(font
					(size 1.27 1.27)
				)
				(justify mirror)
			)
		)
		(duplicate_pad_numbers_are_jumpers no)
		(fp_line
			(start 0.7874 0.4064)
			(end 0.7874 -0.4064)
			(stroke
				(width 0.1524)
				(type default)
			)
			(layer "B.SilkS")
		)
		(fp_line
			(start 0.7874 -0.4064)
			(end -0.7874 -0.4064)
			(stroke
				(width 0.1524)
				(type default)
			)
			(layer "B.SilkS")
		)
		(fp_line
			(start -0.7874 0.4064)
			(end 0.7874 0.4064)
			(stroke
				(width 0.1524)
				(type default)
			)
			(layer "B.SilkS")
		)
		(fp_line
			(start -0.7874 -0.4064)
			(end -0.7874 0.4064)
			(stroke
				(width 0.1524)
				(type default)
			)
			(layer "B.SilkS")
		)
		(fp_line
			(start 0.67945 0.3048)
			(end 0.67945 -0.305054)
			(stroke
				(width 0.1)
				(type default)
			)
			(layer "B.Fab")
		)
		(fp_line
			(start 0.67945 -0.305054)
			(end 0.12065 -0.305054)
			(stroke
				(width 0.1)
				(type default)
			)
			(layer "B.Fab")
		)
		(fp_line
			(start 0.12065 0.3048)
			(end 0.67945 0.3048)
			(stroke
				(width 0.1)
				(type default)
			)
			(layer "B.Fab")
		)
		(fp_line
			(start 0.12065 0.2794)
			(end 0.12065 0.3048)
			(stroke
				(width 0.1)
				(type default)
			)
			(layer "B.Fab")
		)
		(fp_line
			(start 0.12065 -0.2794)
			(end -0.12065 -0.2794)
			(stroke
				(width 0.1)
				(type default)
			)
			(layer "B.Fab")
		)
		(fp_line
			(start 0.12065 -0.305054)
			(end 0.12065 -0.2794)
			(stroke
				(width 0.1)
				(type default)
			)
			(layer "B.Fab")
		)
		(fp_line
			(start -0.120396 0.3048)
			(end -0.120396 0.2794)
			(stroke
				(width 0.1)
				(type default)
			)
			(layer "B.Fab")
		)
		(fp_line
			(start -0.120396 0.2794)
			(end 0.12065 0.2794)
			(stroke
				(width 0.1)
				(type default)
			)
			(layer "B.Fab")
		)
		(fp_line
			(start -0.12065 -0.2794)
			(end -0.12065 -0.3048)
			(stroke
				(width 0.1)
				(type default)
			)
			(layer "B.Fab")
		)
		(fp_line
			(start -0.12065 -0.3048)
			(end -0.67945 -0.3048)
			(stroke
				(width 0.1)
				(type default)
			)
			(layer "B.Fab")
		)
		(fp_line
			(start -0.67945 0.3048)
			(end -0.120396 0.3048)
			(stroke
				(width 0.1)
				(type default)
			)
			(layer "B.Fab")
		)
		(fp_line
			(start -0.67945 -0.3048)
			(end -0.67945 0.3048)
			(stroke
				(width 0.1)
				(type default)
			)
			(layer "B.Fab")
		)
		(pad "1" smd circle
			(at 0.40005 0)
			(size 0 0)
			(layers "B.Cu" "B.Mask" "B.Paste")
			(net "PVDDCR_CPU0_P1")
		)
		(pad "2" smd circle
			(at -0.40005 0)
			(size 0 0)
			(layers "B.Cu" "B.Mask" "B.Paste")
			(net "GND")
		)
	)
	(footprint ""
		(layer "B.Cu")
		(at 38.002718 -346.788994 90)
		(property "Reference" "PC626_3"
			(at 0 0 90)
			(layer "B.SilkS")
			(hide yes)
			(effects
				(font
					(size 1.27 1.27)
				)
				(justify mirror)
			)
		)
		(property "Value" ""
			(at 0 0 90)
			(layer "B.Fab")
			(effects
				(font
					(size 1.27 1.27)
				)
				(justify mirror)
			)
		)
		(duplicate_pad_numbers_are_jumpers no)
		(fp_line
			(start 1.524 -0.762)
			(end -1.524 -0.762)
			(stroke
				(width 0.1524)
				(type default)
			)
			(layer "B.SilkS")
		)
		(fp_line
			(start -1.524 -0.762)
			(end -1.524 0.762)
			(stroke
				(width 0.1524)
				(type default)
			)
			(layer "B.SilkS")
		)
		(fp_line
			(start 1.524 0.762)
			(end 1.524 -0.762)
			(stroke
				(width 0.1524)
				(type default)
			)
			(layer "B.SilkS")
		)
		(fp_line
			(start -1.524 0.762)
			(end 1.524 0.762)
			(stroke
				(width 0.1524)
				(type default)
			)
			(layer "B.SilkS")
		)
		(fp_line
			(start 1.1049 -0.724916)
			(end 1.1049 0.724916)
			(stroke
				(width 0.1)
				(type default)
			)
			(layer "B.Fab")
		)
		(fp_line
			(start -1.1049 -0.724916)
			(end 1.1049 -0.724916)
			(stroke
				(width 0.1)
				(type default)
			)
			(layer "B.Fab")
		)
		(fp_line
			(start 1.1049 0.724916)
			(end -1.1049 0.724916)
			(stroke
				(width 0.1)
				(type default)
			)
			(layer "B.Fab")
		)
		(fp_line
			(start -1.1049 0.724916)
			(end -1.1049 -0.724916)
			(stroke
				(width 0.1)
				(type default)
			)
			(layer "B.Fab")
		)
		(pad "1" smd rect
			(at 0.889 0 90)
			(size 1.016 1.27)
			(layers "B.Cu" "B.Mask" "B.Paste")
			(net "SW_P12V_AUX_PVDDIO_P1_FLT")
		)
		(pad "2" smd rect
			(at -0.889 0 90)
			(size 1.016 1.27)
			(layers "B.Cu" "B.Mask" "B.Paste")
			(net "GND")
		)
	)
	(footprint ""
		(layer "B.Cu")
		(at 127.62738 -162.527234 90)
		(property "Reference" "PR212"
			(at 0 0 90)
			(layer "B.SilkS")
			(hide yes)
			(effects
				(font
					(size 1.27 1.27)
				)
				(justify mirror)
			)
		)
		(property "Value" ""
			(at 0 0 90)
			(layer "B.Fab")
			(effects
				(font
					(size 1.27 1.27)
				)
				(justify mirror)
			)
		)
		(duplicate_pad_numbers_are_jumpers no)
		(fp_line
			(start 0.7874 -0.4064)
			(end -0.7874 -0.4064)
			(stroke
				(width 0.1524)
				(type default)
			)
			(layer "B.SilkS")
		)
		(fp_line
			(start -0.7874 -0.4064)
			(end -0.7874 0.4064)
			(stroke
				(width 0.1524)
				(type default)
			)
			(layer "B.SilkS")
		)
		(fp_line
			(start 0.7874 0.4064)
			(end 0.7874 -0.4064)
			(stroke
				(width 0.1524)
				(type default)
			)
			(layer "B.SilkS")
		)
		(fp_line
			(start -0.7874 0.4064)
			(end 0.7874 0.4064)
			(stroke
				(width 0.1524)
				(type default)
			)
			(layer "B.SilkS")
		)
		(fp_line
			(start 0.67945 -0.305054)
			(end 0.12065 -0.305054)
			(stroke
				(width 0.1)
				(type default)
			)
			(layer "B.Fab")
		)
		(fp_line
			(start 0.12065 -0.305054)
			(end 0.12065 -0.2794)
			(stroke
				(width 0.1)
				(type default)
			)
			(layer "B.Fab")
		)
		(fp_line
			(start -0.12065 -0.3048)
			(end -0.67945 -0.3048)
			(stroke
				(width 0.1)
				(type default)
			)
			(layer "B.Fab")
		)
		(fp_line
			(start -0.67945 -0.3048)
			(end -0.67945 0.3048)
			(stroke
				(width 0.1)
				(type default)
			)
			(layer "B.Fab")
		)
		(fp_line
			(start 0.12065 -0.2794)
			(end -0.12065 -0.2794)
			(stroke
				(width 0.1)
				(type default)
			)
			(layer "B.Fab")
		)
		(fp_line
			(start -0.12065 -0.2794)
			(end -0.12065 -0.3048)
			(stroke
				(width 0.1)
				(type default)
			)
			(layer "B.Fab")
		)
		(fp_line
			(start 0.12065 0.2794)
			(end 0.12065 0.3048)
			(stroke
				(width 0.1)
				(type default)
			)
			(layer "B.Fab")
		)
		(fp_line
			(start -0.120396 0.2794)
			(end 0.12065 0.2794)
			(stroke
				(width 0.1)
				(type default)
			)
			(layer "B.Fab")
		)
		(fp_line
			(start 0.67945 0.3048)
			(end 0.67945 -0.305054)
			(stroke
				(width 0.1)
				(type default)
			)
			(layer "B.Fab")
		)
		(fp_line
			(start 0.12065 0.3048)
			(end 0.67945 0.3048)
			(stroke
				(width 0.1)
				(type default)
			)
			(layer "B.Fab")
		)
		(fp_line
			(start -0.120396 0.3048)
			(end -0.120396 0.2794)
			(stroke
				(width 0.1)
				(type default)
			)
			(layer "B.Fab")
		)
		(fp_line
			(start -0.67945 0.3048)
			(end -0.120396 0.3048)
			(stroke
				(width 0.1)
				(type default)
			)
			(layer "B.Fab")
		)
		(pad "1" smd circle
			(at 0.40005 0 270)
			(size 0 0)
			(layers "B.Cu" "B.Mask" "B.Paste")
			(net "PVDDCR_SOC_P1_VOS2")
		)
		(pad "2" smd circle
			(at -0.40005 0 270)
			(size 0 0)
			(layers "B.Cu" "B.Mask" "B.Paste")
			(net "PVDDCR_SOC_P1")
		)
	)
	(footprint ""
		(layer "B.Cu")
		(at 276.54377 -350.65589 -90)
		(property "Reference" "PC188_4"
			(at 0 0 90)
			(layer "B.SilkS")
			(hide yes)
			(effects
				(font
					(size 1.27 1.27)
				)
				(justify mirror)
			)
		)
		(property "Value" ""
			(at 0 0 90)
			(layer "B.Fab")
			(effects
				(font
					(size 1.27 1.27)
				)
				(justify mirror)
			)
		)
		(duplicate_pad_numbers_are_jumpers no)
		(fp_line
			(start -1.524 0.762)
			(end 1.524 0.762)
			(stroke
				(width 0.1524)
				(type default)
			)
			(layer "B.SilkS")
		)
		(fp_line
			(start 1.524 0.762)
			(end 1.524 -0.762)
			(stroke
				(width 0.1524)
				(type default)
			)
			(layer "B.SilkS")
		)
		(fp_line
			(start -1.524 -0.762)
			(end -1.524 0.762)
			(stroke
				(width 0.1524)
				(type default)
			)
			(layer "B.SilkS")
		)
		(fp_line
			(start 1.524 -0.762)
			(end -1.524 -0.762)
			(stroke
				(width 0.1524)
				(type default)
			)
			(layer "B.SilkS")
		)
		(fp_line
			(start -1.1049 0.724916)
			(end -1.1049 -0.724916)
			(stroke
				(width 0.1)
				(type default)
			)
			(layer "B.Fab")
		)
		(fp_line
			(start 1.1049 0.724916)
			(end -1.1049 0.724916)
			(stroke
				(width 0.1)
				(type default)
			)
			(layer "B.Fab")
		)
		(fp_line
			(start -1.1049 -0.724916)
			(end 1.1049 -0.724916)
			(stroke
				(width 0.1)
				(type default)
			)
			(layer "B.Fab")
		)
		(fp_line
			(start 1.1049 -0.724916)
			(end 1.1049 0.724916)
			(stroke
				(width 0.1)
				(type default)
			)
			(layer "B.Fab")
		)
		(pad "1" smd rect
			(at 0.889 0 270)
			(size 1.016 1.27)
			(layers "B.Cu" "B.Mask" "B.Paste")
			(net "SW_P12V_AUX_PVDDIO_P0_FLT")
		)
		(pad "2" smd rect
			(at -0.889 0 270)
			(size 1.016 1.27)
			(layers "B.Cu" "B.Mask" "B.Paste")
			(net "GND")
		)
	)
	(footprint ""
		(layer "B.Cu")
		(at 404.043642 -349.215964 -90)
		(property "Reference" "R6121"
			(at 0 0 90)
			(layer "B.SilkS")
			(hide yes)
			(effects
				(font
					(size 1.27 1.27)
				)
				(justify mirror)
			)
		)
		(property "Value" ""
			(at 0 0 90)
			(layer "B.Fab")
			(effects
				(font
					(size 1.27 1.27)
				)
				(justify mirror)
			)
		)
		(duplicate_pad_numbers_are_jumpers no)
		(fp_line
			(start -0.7874 0.4064)
			(end 0.7874 0.4064)
			(stroke
				(width 0.1524)
				(type default)
			)
			(layer "B.SilkS")
		)
		(fp_line
			(start 0.7874 0.4064)
			(end 0.7874 -0.4064)
			(stroke
				(width 0.1524)
				(type default)
			)
			(layer "B.SilkS")
		)
		(fp_line
			(start -0.7874 -0.4064)
			(end -0.7874 0.4064)
			(stroke
				(width 0.1524)
				(type default)
			)
			(layer "B.SilkS")
		)
		(fp_line
			(start 0.7874 -0.4064)
			(end -0.7874 -0.4064)
			(stroke
				(width 0.1524)
				(type default)
			)
			(layer "B.SilkS")
		)
		(fp_line
			(start -0.67945 0.3048)
			(end -0.120396 0.3048)
			(stroke
				(width 0.1)
				(type default)
			)
			(layer "B.Fab")
		)
		(fp_line
			(start -0.120396 0.3048)
			(end -0.120396 0.2794)
			(stroke
				(width 0.1)
				(type default)
			)
			(layer "B.Fab")
		)
		(fp_line
			(start 0.12065 0.3048)
			(end 0.67945 0.3048)
			(stroke
				(width 0.1)
				(type default)
			)
			(layer "B.Fab")
		)
		(fp_line
			(start 0.67945 0.3048)
			(end 0.67945 -0.305054)
			(stroke
				(width 0.1)
				(type default)
			)
			(layer "B.Fab")
		)
		(fp_line
			(start -0.120396 0.2794)
			(end 0.12065 0.2794)
			(stroke
				(width 0.1)
				(type default)
			)
			(layer "B.Fab")
		)
		(fp_line
			(start 0.12065 0.2794)
			(end 0.12065 0.3048)
			(stroke
				(width 0.1)
				(type default)
			)
			(layer "B.Fab")
		)
		(fp_line
			(start -0.12065 -0.2794)
			(end -0.12065 -0.3048)
			(stroke
				(width 0.1)
				(type default)
			)
			(layer "B.Fab")
		)
		(fp_line
			(start 0.12065 -0.2794)
			(end -0.12065 -0.2794)
			(stroke
				(width 0.1)
				(type default)
			)
			(layer "B.Fab")
		)
		(fp_line
			(start -0.67945 -0.3048)
			(end -0.67945 0.3048)
			(stroke
				(width 0.1)
				(type default)
			)
			(layer "B.Fab")
		)
		(fp_line
			(start -0.12065 -0.3048)
			(end -0.67945 -0.3048)
			(stroke
				(width 0.1)
				(type default)
			)
			(layer "B.Fab")
		)
		(fp_line
			(start 0.12065 -0.305054)
			(end 0.12065 -0.2794)
			(stroke
				(width 0.1)
				(type default)
			)
			(layer "B.Fab")
		)
		(fp_line
			(start 0.67945 -0.305054)
			(end 0.12065 -0.305054)
			(stroke
				(width 0.1)
				(type default)
			)
			(layer "B.Fab")
		)
		(pad "1" smd circle
			(at 0.40005 0 90)
			(size 0 0)
			(layers "B.Cu" "B.Mask" "B.Paste")
			(net "PVDD18_S5_P0")
		)
		(pad "2" smd circle
			(at -0.40005 0 90)
			(size 0 0)
			(layers "B.Cu" "B.Mask" "B.Paste")
			(net "FM_BOARD_SKU_ID3")
		)
	)
)
